# S9S_MB_2U (Grand Teton) — schematic netlist excerpt (pin names and nets, part order shuffled) for the footprints in the layout excerpt that follows; sources: Cadence DE-HDL packaged netlist, KiCad conversion of 03242023_DA0F0TMBIJ0_F0T_Motherboard_J_brd_V01_OCP.brd

C449  Q_CAP  47UF 4V 20% X6S  pkg C0805  page 78 : A = PVCCFA_EHV_FIVRA_CPU1 ; B = GND
R494  Q_RES  1K 1% CHIP  pkg 0402LF  page 182 : A = P3V3_AUX ; B = IRQ_LVC3_WAKE_N
C398  Q_CAP  47UF 4V 20% X6S  pkg C0805  page 76 : A = PVCCIN_CPU0 ; B = GND

(kicad_pcb
	(version 20260206)
	(generator "pcbnew")
	(generator_version "10.0")
	(general
		(thickness 1.6)
		(legacy_teardrops no)
	)
	(paper "A4")
	(title_block
		(title "03242023_DA0F0TMBIJ0_F0T_Motherboard_J_brd_V01_OCP.brd")
		(comment 1 "Grand Teton / footprints 5032-5034 of 6105")
	)
	(layers
		(0 "F.Cu" signal "TOP")
		(4 "In1.Cu" signal "GND")
		(6 "In2.Cu" signal "IN1")
		(8 "In3.Cu" signal "GND1")
		(10 "In4.Cu" signal "IN2")
		(12 "In5.Cu" signal "GND2")
		(14 "In6.Cu" signal "IN3")
		(16 "In7.Cu" signal "GND3")
		(18 "In8.Cu" signal "VCC")
		(20 "In9.Cu" signal "VCC1")
		(22 "In10.Cu" signal "GND4")
		(24 "In11.Cu" signal "IN4")
		(26 "In12.Cu" signal "GND5")
		(28 "In13.Cu" signal "IN5")
		(30 "In14.Cu" signal "GND6")
		(32 "In15.Cu" signal "IN6")
		(34 "In16.Cu" signal "GND7")
		(2 "B.Cu" signal "BOTTOM")
		(9 "F.Adhes" user "F.Adhesive")
		(11 "B.Adhes" user "B.Adhesive")
		(13 "F.Paste" user "Package Geometry/Pastemask Top")
		(15 "B.Paste" user "Package Geometry/Pastemask Bottom")
		(5 "F.SilkS" user "Ref Des/Silkscreen Top")
		(7 "B.SilkS" user "Ref Des/Silkscreen Bottom")
		(1 "F.Mask" user "Board Geometry/Soldermask Top")
		(3 "B.Mask" user "Board Geometry/Soldermask Bottom")
		(17 "Dwgs.User" user "User.Drawings")
		(19 "Cmts.User" user "User.Comments")
		(21 "Eco1.User" user "User.Eco1")
		(23 "Eco2.User" user "User.Eco2")
		(25 "Edge.Cuts" user "Board Geometry/Outline")
		(27 "Margin" user)
		(31 "F.CrtYd" user "Package Geometry/Place Bound Top")
		(29 "B.CrtYd" user "Package Geometry/Place Bound Bottom")
		(35 "F.Fab" user "Ref Des/Assembly Top")
		(33 "B.Fab" user "Ref Des/Assembly Bottom")
	)
	(footprint ""
		(layer "B.Cu")
		(at 369.485418 -296.054526 180)
		(property "Reference" "C398"
			(at 0 0 0)
			(layer "B.SilkS")
			(hide yes)
			(effects
				(font
					(size 1.27 1.27)
				)
				(justify mirror)
			)
		)
		(property "Value" ""
			(at 0 0 0)
			(layer "B.Fab")
			(effects
				(font
					(size 1.27 1.27)
				)
				(justify mirror)
			)
		)
		(duplicate_pad_numbers_are_jumpers no)
		(fp_line
			(start 1.524 0.762)
			(end 1.524 -0.762)
			(stroke
				(width 0.1524)
				(type default)
			)
			(layer "B.SilkS")
		)
		(fp_line
			(start 1.524 -0.762)
			(end -1.524 -0.762)
			(stroke
				(width 0.1524)
				(type default)
			)
			(layer "B.SilkS")
		)
		(fp_line
			(start -1.524 0.762)
			(end 1.524 0.762)
			(stroke
				(width 0.1524)
				(type default)
			)
			(layer "B.SilkS")
		)
		(fp_line
			(start -1.524 -0.762)
			(end -1.524 0.762)
			(stroke
				(width 0.1524)
				(type default)
			)
			(layer "B.SilkS")
		)
		(fp_line
			(start 1.1049 0.724916)
			(end -1.1049 0.724916)
			(stroke
				(width 0.1)
				(type default)
			)
			(layer "B.Fab")
		)
		(fp_line
			(start 1.1049 -0.724916)
			(end 1.1049 0.724916)
			(stroke
				(width 0.1)
				(type default)
			)
			(layer "B.Fab")
		)
		(fp_line
			(start -1.1049 0.724916)
			(end -1.1049 -0.724916)
			(stroke
				(width 0.1)
				(type default)
			)
			(layer "B.Fab")
		)
		(fp_line
			(start -1.1049 -0.724916)
			(end 1.1049 -0.724916)
			(stroke
				(width 0.1)
				(type default)
			)
			(layer "B.Fab")
		)
		(pad "1" smd rect
			(at 0.889 0 180)
			(size 1.016 1.27)
			(layers "B.Cu" "B.Mask" "B.Paste")
			(net "PVCCIN_CPU0")
		)
		(pad "2" smd rect
			(at -0.889 0 180)
			(size 1.016 1.27)
			(layers "B.Cu" "B.Mask" "B.Paste")
			(net "GND")
		)
	)
	(footprint ""
		(layer "B.Cu")
		(at 312.443622 -34.102548 180)
		(property "Reference" "R494"
			(at 0 0 0)
			(layer "B.SilkS")
			(hide yes)
			(effects
				(font
					(size 1.27 1.27)
				)
				(justify mirror)
			)
		)
		(property "Value" ""
			(at 0 0 0)
			(layer "B.Fab")
			(effects
				(font
					(size 1.27 1.27)
				)
				(justify mirror)
			)
		)
		(duplicate_pad_numbers_are_jumpers no)
		(fp_line
			(start 0.7874 0.4064)
			(end 0.7874 -0.4064)
			(stroke
				(width 0.1524)
				(type default)
			)
			(layer "B.SilkS")
		)
		(fp_line
			(start 0.7874 -0.4064)
			(end -0.7874 -0.4064)
			(stroke
				(width 0.1524)
				(type default)
			)
			(layer "B.SilkS")
		)
		(fp_line
			(start -0.7874 0.4064)
			(end 0.7874 0.4064)
			(stroke
				(width 0.1524)
				(type default)
			)
			(layer "B.SilkS")
		)
		(fp_line
			(start -0.7874 -0.4064)
			(end -0.7874 0.4064)
			(stroke
				(width 0.1524)
				(type default)
			)
			(layer "B.SilkS")
		)
		(fp_line
			(start 0.67945 0.3048)
			(end 0.67945 -0.305054)
			(stroke
				(width 0.1)
				(type default)
			)
			(layer "B.Fab")
		)
		(fp_line
			(start 0.67945 -0.305054)
			(end 0.12065 -0.305054)
			(stroke
				(width 0.1)
				(type default)
			)
			(layer "B.Fab")
		)
		(fp_line
			(start 0.12065 0.3048)
			(end 0.67945 0.3048)
			(stroke
				(width 0.1)
				(type default)
			)
			(layer "B.Fab")
		)
		(fp_line
			(start 0.12065 0.2794)
			(end 0.12065 0.3048)
			(stroke
				(width 0.1)
				(type default)
			)
			(layer "B.Fab")
		)
		(fp_line
			(start 0.12065 -0.2794)
			(end -0.12065 -0.2794)
			(stroke
				(width 0.1)
				(type default)
			)
			(layer "B.Fab")
		)
		(fp_line
			(start 0.12065 -0.305054)
			(end 0.12065 -0.2794)
			(stroke
				(width 0.1)
				(type default)
			)
			(layer "B.Fab")
		)
		(fp_line
			(start -0.120396 0.3048)
			(end -0.120396 0.2794)
			(stroke
				(width 0.1)
				(type default)
			)
			(layer "B.Fab")
		)
		(fp_line
			(start -0.120396 0.2794)
			(end 0.12065 0.2794)
			(stroke
				(width 0.1)
				(type default)
			)
			(layer "B.Fab")
		)
		(fp_line
			(start -0.12065 -0.2794)
			(end -0.12065 -0.3048)
			(stroke
				(width 0.1)
				(type default)
			)
			(layer "B.Fab")
		)
		(fp_line
			(start -0.12065 -0.3048)
			(end -0.67945 -0.3048)
			(stroke
				(width 0.1)
				(type default)
			)
			(layer "B.Fab")
		)
		(fp_line
			(start -0.67945 0.3048)
			(end -0.120396 0.3048)
			(stroke
				(width 0.1)
				(type default)
			)
			(layer "B.Fab")
		)
		(fp_line
			(start -0.67945 -0.3048)
			(end -0.67945 0.3048)
			(stroke
				(width 0.1)
				(type default)
			)
			(layer "B.Fab")
		)
		(pad "1" smd circle
			(at 0.40005 0)
			(size 0 0)
			(layers "B.Cu" "B.Mask" "B.Paste")
			(net "P3V3_AUX")
		)
		(pad "2" smd circle
			(at -0.40005 0)
			(size 0 0)
			(layers "B.Cu" "B.Mask" "B.Paste")
			(net "IRQ_LVC3_WAKE_N")
		)
	)
	(footprint ""
		(layer "B.Cu")
		(at 118.18112 -259.53212 90)
		(property "Reference" "C449"
			(at 0 0 90)
			(layer "B.SilkS")
			(hide yes)
			(effects
				(font
					(size 1.27 1.27)
				)
				(justify mirror)
			)
		)
		(property "Value" ""
			(at 0 0 90)
			(layer "B.Fab")
			(effects
				(font
					(size 1.27 1.27)
				)
				(justify mirror)
			)
		)
		(duplicate_pad_numbers_are_jumpers no)
		(fp_line
			(start 1.524 -0.762)
			(end -1.524 -0.762)
			(stroke
				(width 0.1524)
				(type default)
			)
			(layer "B.SilkS")
		)
		(fp_line
			(start -1.524 -0.762)
			(end -1.524 0.762)
			(stroke
				(width 0.1524)
				(type default)
			)
			(layer "B.SilkS")
		)
		(fp_line
			(start 1.524 0.762)
			(end 1.524 -0.762)
			(stroke
				(width 0.1524)
				(type default)
			)
			(layer "B.SilkS")
		)
		(fp_line
			(start -1.524 0.762)
			(end 1.524 0.762)
			(stroke
				(width 0.1524)
				(type default)
			)
			(layer "B.SilkS")
		)
		(fp_line
			(start 1.1049 -0.724916)
			(end 1.1049 0.724916)
			(stroke
				(width 0.1)
				(type default)
			)
			(layer "B.Fab")
		)
		(fp_line
			(start -1.1049 -0.724916)
			(end 1.1049 -0.724916)
			(stroke
				(width 0.1)
				(type default)
			)
			(layer "B.Fab")
		)
		(fp_line
			(start 1.1049 0.724916)
			(end -1.1049 0.724916)
			(stroke
				(width 0.1)
				(type default)
			)
			(layer "B.Fab")
		)
		(fp_line
			(start -1.1049 0.724916)
			(end -1.1049 -0.724916)
			(stroke
				(width 0.1)
				(type default)
			)
			(layer "B.Fab")
		)
		(pad "1" smd rect
			(at 0.889 0 90)
			(size 1.016 1.27)
			(layers "B.Cu" "B.Mask" "B.Paste")
			(net "PVCCFA_EHV_FIVRA_CPU1")
		)
		(pad "2" smd rect
			(at -0.889 0 90)
			(size 1.016 1.27)
			(layers "B.Cu" "B.Mask" "B.Paste")
			(net "GND")
		)
	)
)
